# S9S_MB_2U (Grand Teton) — schematic netlist excerpt (pin names and nets, part order shuffled) for the footprints in the layout excerpt that follows; sources: Cadence DE-HDL packaged netlist, KiCad conversion of 03242023_DA0F0TMBIJ0_F0T_Motherboard_J_brd_V01_OCP.brd

C1172  Q_CAP  100NF 50V 10% X7R  pkg C0402  page 260 : A = P5V ; B = GND
PR2531  Q_RES  10 1% EMPTY  pkg 0402LF  page 304 : A = P12V_HSC_GATE_G4 ; B = P12V_HSC_GATE2

(kicad_pcb
	(version 20260206)
	(generator "pcbnew")
	(generator_version "10.0")
	(general
		(thickness 1.6)
		(legacy_teardrops no)
	)
	(paper "A4")
	(title_block
		(title "03242023_DA0F0TMBIJ0_F0T_Motherboard_J_brd_V01_OCP.brd")
		(comment 1 "Grand Teton / footprints 3615-3616 of 6105")
	)
	(layers
		(0 "F.Cu" signal "TOP")
		(4 "In1.Cu" signal "GND")
		(6 "In2.Cu" signal "IN1")
		(8 "In3.Cu" signal "GND1")
		(10 "In4.Cu" signal "IN2")
		(12 "In5.Cu" signal "GND2")
		(14 "In6.Cu" signal "IN3")
		(16 "In7.Cu" signal "GND3")
		(18 "In8.Cu" signal "VCC")
		(20 "In9.Cu" signal "VCC1")
		(22 "In10.Cu" signal "GND4")
		(24 "In11.Cu" signal "IN4")
		(26 "In12.Cu" signal "GND5")
		(28 "In13.Cu" signal "IN5")
		(30 "In14.Cu" signal "GND6")
		(32 "In15.Cu" signal "IN6")
		(34 "In16.Cu" signal "GND7")
		(2 "B.Cu" signal "BOTTOM")
		(9 "F.Adhes" user "F.Adhesive")
		(11 "B.Adhes" user "B.Adhesive")
		(13 "F.Paste" user "Package Geometry/Pastemask Top")
		(15 "B.Paste" user "Package Geometry/Pastemask Bottom")
		(5 "F.SilkS" user "Ref Des/Silkscreen Top")
		(7 "B.SilkS" user "Ref Des/Silkscreen Bottom")
		(1 "F.Mask" user "Board Geometry/Soldermask Top")
		(3 "B.Mask" user "Board Geometry/Soldermask Bottom")
		(17 "Dwgs.User" user "User.Drawings")
		(19 "Cmts.User" user "User.Comments")
		(21 "Eco1.User" user "User.Eco1")
		(23 "Eco2.User" user "User.Eco2")
		(25 "Edge.Cuts" user "Board Geometry/Outline")
		(27 "Margin" user)
		(31 "F.CrtYd" user "Package Geometry/Place Bound Top")
		(29 "B.CrtYd" user "Package Geometry/Place Bound Bottom")
		(35 "F.Fab" user "Ref Des/Assembly Top")
		(33 "B.Fab" user "Ref Des/Assembly Bottom")
	)
	(footprint ""
		(layer "F.Cu")
		(at 274.271486 -394.17117)
		(property "Reference" "PR2531"
			(at 0 0 0)
			(layer "F.SilkS")
			(hide yes)
			(effects
				(font
					(size 1.27 1.27)
				)
			)
		)
		(property "Value" ""
			(at 0 0 0)
			(layer "F.Fab")
			(effects
				(font
					(size 1.27 1.27)
				)
			)
		)
		(duplicate_pad_numbers_are_jumpers no)
		(fp_line
			(start -0.7874 -0.4064)
			(end 0.7874 -0.4064)
			(stroke
				(width 0.1524)
				(type default)
			)
			(layer "F.SilkS")
		)
		(fp_line
			(start -0.7874 0.4064)
			(end -0.7874 -0.4064)
			(stroke
				(width 0.1524)
				(type default)
			)
			(layer "F.SilkS")
		)
		(fp_line
			(start 0.7874 -0.4064)
			(end 0.7874 0.4064)
			(stroke
				(width 0.1524)
				(type default)
			)
			(layer "F.SilkS")
		)
		(fp_line
			(start 0.7874 0.4064)
			(end -0.7874 0.4064)
			(stroke
				(width 0.1524)
				(type default)
			)
			(layer "F.SilkS")
		)
		(fp_line
			(start -0.67945 -0.305054)
			(end -0.12065 -0.305054)
			(stroke
				(width 0.1)
				(type default)
			)
			(layer "F.Fab")
		)
		(fp_line
			(start -0.67945 0.3048)
			(end -0.67945 -0.305054)
			(stroke
				(width 0.1)
				(type default)
			)
			(layer "F.Fab")
		)
		(fp_line
			(start -0.12065 -0.305054)
			(end -0.12065 -0.2794)
			(stroke
				(width 0.1)
				(type default)
			)
			(layer "F.Fab")
		)
		(fp_line
			(start -0.12065 -0.2794)
			(end 0.12065 -0.2794)
			(stroke
				(width 0.1)
				(type default)
			)
			(layer "F.Fab")
		)
		(fp_line
			(start -0.12065 0.2794)
			(end -0.12065 0.3048)
			(stroke
				(width 0.1)
				(type default)
			)
			(layer "F.Fab")
		)
		(fp_line
			(start -0.12065 0.3048)
			(end -0.67945 0.3048)
			(stroke
				(width 0.1)
				(type default)
			)
			(layer "F.Fab")
		)
		(fp_line
			(start 0.120396 0.2794)
			(end -0.12065 0.2794)
			(stroke
				(width 0.1)
				(type default)
			)
			(layer "F.Fab")
		)
		(fp_line
			(start 0.120396 0.3048)
			(end 0.120396 0.2794)
			(stroke
				(width 0.1)
				(type default)
			)
			(layer "F.Fab")
		)
		(fp_line
			(start 0.12065 -0.3048)
			(end 0.67945 -0.3048)
			(stroke
				(width 0.1)
				(type default)
			)
			(layer "F.Fab")
		)
		(fp_line
			(start 0.12065 -0.2794)
			(end 0.12065 -0.3048)
			(stroke
				(width 0.1)
				(type default)
			)
			(layer "F.Fab")
		)
		(fp_line
			(start 0.67945 -0.3048)
			(end 0.67945 0.3048)
			(stroke
				(width 0.1)
				(type default)
			)
			(layer "F.Fab")
		)
		(fp_line
			(start 0.67945 0.3048)
			(end 0.120396 0.3048)
			(stroke
				(width 0.1)
				(type default)
			)
			(layer "F.Fab")
		)
		(pad "1" smd circle
			(at -0.40005 0)
			(size 0 0)
			(layers "F.Cu" "F.Mask" "F.Paste")
			(net "P12V_HSC_GATE_G4")
		)
		(pad "2" smd circle
			(at 0.40005 0)
			(size 0 0)
			(layers "F.Cu" "F.Mask" "F.Paste")
			(net "P12V_HSC_GATE2")
		)
	)
	(footprint ""
		(layer "F.Cu")
		(at 417.43757 -45.83684 180)
		(property "Reference" "C1172"
			(at 0 0 180)
			(layer "F.SilkS")
			(hide yes)
			(effects
				(font
					(size 1.27 1.27)
				)
			)
		)
		(property "Value" ""
			(at 0 0 180)
			(layer "F.Fab")
			(effects
				(font
					(size 1.27 1.27)
				)
			)
		)
		(duplicate_pad_numbers_are_jumpers no)
		(fp_line
			(start 0.7874 0.4064)
			(end -0.7874 0.4064)
			(stroke
				(width 0.1524)
				(type default)
			)
			(layer "F.SilkS")
		)
		(fp_line
			(start 0.7874 -0.4064)
			(end 0.7874 0.4064)
			(stroke
				(width 0.1524)
				(type default)
			)
			(layer "F.SilkS")
		)
		(fp_line
			(start -0.7874 0.4064)
			(end -0.7874 -0.4064)
			(stroke
				(width 0.1524)
				(type default)
			)
			(layer "F.SilkS")
		)
		(fp_line
			(start -0.7874 -0.4064)
			(end 0.7874 -0.4064)
			(stroke
				(width 0.1524)
				(type default)
			)
			(layer "F.SilkS")
		)
		(fp_line
			(start 0.67945 0.3048)
			(end 0.120396 0.3048)
			(stroke
				(width 0.1)
				(type default)
			)
			(layer "F.Fab")
		)
		(fp_line
			(start 0.67945 -0.3048)
			(end 0.67945 0.3048)
			(stroke
				(width 0.1)
				(type default)
			)
			(layer "F.Fab")
		)
		(fp_line
			(start 0.12065 -0.2794)
			(end 0.12065 -0.3048)
			(stroke
				(width 0.1)
				(type default)
			)
			(layer "F.Fab")
		)
		(fp_line
			(start 0.12065 -0.3048)
			(end 0.67945 -0.3048)
			(stroke
				(width 0.1)
				(type default)
			)
			(layer "F.Fab")
		)
		(fp_line
			(start 0.120396 0.3048)
			(end 0.120396 0.2794)
			(stroke
				(width 0.1)
				(type default)
			)
			(layer "F.Fab")
		)
		(fp_line
			(start 0.120396 0.2794)
			(end -0.12065 0.2794)
			(stroke
				(width 0.1)
				(type default)
			)
			(layer "F.Fab")
		)
		(fp_line
			(start -0.12065 0.3048)
			(end -0.67945 0.3048)
			(stroke
				(width 0.1)
				(type default)
			)
			(layer "F.Fab")
		)
		(fp_line
			(start -0.12065 0.2794)
			(end -0.12065 0.3048)
			(stroke
				(width 0.1)
				(type default)
			)
			(layer "F.Fab")
		)
		(fp_line
			(start -0.12065 -0.2794)
			(end 0.12065 -0.2794)
			(stroke
				(width 0.1)
				(type default)
			)
			(layer "F.Fab")
		)
		(fp_line
			(start -0.12065 -0.305054)
			(end -0.12065 -0.2794)
			(stroke
				(width 0.1)
				(type default)
			)
			(layer "F.Fab")
		)
		(fp_line
			(start -0.67945 0.3048)
			(end -0.67945 -0.305054)
			(stroke
				(width 0.1)
				(type default)
			)
			(layer "F.Fab")
		)
		(fp_line
			(start -0.67945 -0.305054)
			(end -0.12065 -0.305054)
			(stroke
				(width 0.1)
				(type default)
			)
			(layer "F.Fab")
		)
		(pad "1" smd circle
			(at -0.40005 0 180)
			(size 0 0)
			(layers "F.Cu" "F.Mask" "F.Paste")
			(net "P5V")
		)
		(pad "2" smd circle
			(at 0.40005 0 180)
			(size 0 0)
			(layers "F.Cu" "F.Mask" "F.Paste")
			(net "GND")
		)
	)
)
